(kicad_pcb
	(version 20260206)
	(generator "pcbnew")
	(generator_version "10.0")
	(general
		(thickness 1.6)
		(legacy_teardrops no)
	)
	(paper "A4")
	(title_block
		(title "Wiwynn_Tioga_Pass_MB.brd")
		(comment 1 "Tioga Pass / footprints 2344-2350 of 4770")
	)
	(layers
		(0 "F.Cu" signal "TOP")
		(4 "In1.Cu" signal "L2GND")
		(6 "In2.Cu" signal "L3")
		(8 "In3.Cu" signal "L4GND")
		(10 "In4.Cu" signal "L5")
		(12 "In5.Cu" signal "L6GND")
		(14 "In6.Cu" signal "L7VCC")
		(16 "In7.Cu" signal "L8VCC")
		(18 "In8.Cu" signal "L9GND")
		(20 "In9.Cu" signal "L10")
		(22 "In10.Cu" signal "L11GND")
		(24 "In11.Cu" signal "L12")
		(26 "In12.Cu" signal "L13GND")
		(2 "B.Cu" signal "BOTTOM")
		(9 "F.Adhes" user "F.Adhesive")
		(11 "B.Adhes" user "B.Adhesive")
		(13 "F.Paste" user "Package Geometry/Pastemask Top")
		(15 "B.Paste" user "Package Geometry/Pastemask Bottom")
		(5 "F.SilkS" user "Ref Des/Silkscreen Top")
		(7 "B.SilkS" user "Ref Des/Silkscreen Bottom")
		(1 "F.Mask" user "Board Geometry/Soldermask Top")
		(3 "B.Mask" user "Board Geometry/Soldermask Bottom")
		(17 "Dwgs.User" user "User.Drawings")
		(19 "Cmts.User" user "User.Comments")
		(21 "Eco1.User" user "User.Eco1")
		(23 "Eco2.User" user "User.Eco2")
		(25 "Edge.Cuts" user "Board Geometry/Outline")
		(27 "Margin" user)
		(31 "F.CrtYd" user "Package Geometry/Place Bound Top")
		(29 "B.CrtYd" user "Package Geometry/Place Bound Bottom")
		(35 "F.Fab" user "Ref Des/Assembly Top")
		(33 "B.Fab" user "Ref Des/Assembly Bottom")
	)
	(footprint ""
		(layer "B.Cu")
		(at 416.30092 -37.20338 -90)
		(property "Reference" "C25W26"
			(at 0.8382 -0.67818 270)
			(unlocked yes)
			(layer "B.SilkS")
			(effects
				(font
					(size 0.4064 0.254)
					(thickness 0.1524)
				)
				(justify left mirror)
			)
		)
		(property "Value" ""
			(at 0 0 90)
			(layer "B.Fab")
			(effects
				(font
					(size 1.27 1.27)
				)
				(justify mirror)
			)
		)
		(duplicate_pad_numbers_are_jumpers no)
		(fp_poly
			(pts
				(xy -0.3048 -0.1016) (xy -0.3048 0.9906) (xy 0.3048 0.9906) (xy 0.3048 -0.1016)
			)
			(stroke
				(width 0)
				(type default)
			)
			(fill no)
			(layer "B.CrtYd")
		)
		(fp_line
			(start -0.3048 0.9906)
			(end -0.3048 -0.1016)
			(stroke
				(width 0.1)
				(type default)
			)
			(layer "B.Fab")
		)
		(fp_line
			(start 0.3048 0.9906)
			(end -0.3048 0.9906)
			(stroke
				(width 0.1)
				(type default)
			)
			(layer "B.Fab")
		)
		(fp_line
			(start -0.3048 -0.1016)
			(end 0.3048 -0.1016)
			(stroke
				(width 0.1)
				(type default)
			)
			(layer "B.Fab")
		)
		(fp_line
			(start 0.3048 -0.1016)
			(end 0.3048 0.9906)
			(stroke
				(width 0.1)
				(type default)
			)
			(layer "B.Fab")
		)
		(pad "1" smd rect
			(at 0 0 90)
			(size 0.508 0.508)
			(layers "B.Cu" "B.Mask" "B.Paste")
			(net "P1V15_AUX_BMC")
		)
		(pad "2" smd rect
			(at 0 0.889 90)
			(size 0.508 0.508)
			(layers "B.Cu" "B.Mask" "B.Paste")
			(net "GND")
		)
		(zone
			(layer "B.Cu")
			(hatch none 0.5)
			(connect_pads
				(clearance 0)
			)
			(min_thickness 0.25)
			(keepout
				(tracks not_allowed)
				(vias allowed)
				(pads allowed)
				(copperpour not_allowed)
				(footprints allowed)
			)
			(placement
				(enabled no)
				(sheetname "")
			)
			(fill
				(thermal_gap 0.5)
				(thermal_bridge_width 0.5)
				(island_removal_mode 0)
			)
			(polygon
				(pts
					(xy 415.66592 -36.94938) (xy 415.66592 -37.45738) (xy 416.04692 -37.45738) (xy 416.04692 -36.94938)
				)
			)
		)
		(zone
			(layer "B.Cu")
			(hatch none 0.5)
			(connect_pads
				(clearance 0)
			)
			(min_thickness 0.25)
			(keepout
				(tracks allowed)
				(vias not_allowed)
				(pads allowed)
				(copperpour not_allowed)
				(footprints allowed)
			)
			(placement
				(enabled no)
				(sheetname "")
			)
			(fill
				(thermal_gap 0.5)
				(thermal_bridge_width 0.5)
				(island_removal_mode 0)
			)
			(polygon
				(pts
					(xy 416.04692 -36.94938) (xy 416.04692 -37.45738) (xy 415.66592 -37.45738) (xy 415.66592 -36.94938)
				)
			)
		)
	)
	(footprint ""
		(layer "B.Cu")
		(at 193.8528 -102.6668 180)
		(property "Reference" "R6N14"
			(at 0 0 0)
			(layer "B.SilkS")
			(hide yes)
			(effects
				(font
					(size 1.27 1.27)
				)
				(justify mirror)
			)
		)
		(property "Value" ""
			(at 0 0 0)
			(layer "B.Fab")
			(effects
				(font
					(size 1.27 1.27)
				)
				(justify mirror)
			)
		)
		(duplicate_pad_numbers_are_jumpers no)
		(fp_poly
			(pts
				(xy 0.2794 -0.1016) (xy -0.2794 -0.1016) (xy -0.2794 0.9906) (xy 0.2794 0.9906)
			)
			(stroke
				(width 0)
				(type default)
			)
			(fill no)
			(layer "B.CrtYd")
		)
		(fp_line
			(start 0.2794 0.9906)
			(end -0.2794 0.9906)
			(stroke
				(width 0.1)
				(type default)
			)
			(layer "B.Fab")
		)
		(fp_line
			(start 0.2794 -0.1016)
			(end 0.2794 0.9906)
			(stroke
				(width 0.1)
				(type default)
			)
			(layer "B.Fab")
		)
		(fp_line
			(start -0.2794 0.9906)
			(end -0.2794 -0.1016)
			(stroke
				(width 0.1)
				(type default)
			)
			(layer "B.Fab")
		)
		(fp_line
			(start -0.2794 -0.1016)
			(end 0.2794 -0.1016)
			(stroke
				(width 0.1)
				(type default)
			)
			(layer "B.Fab")
		)
		(pad "1" smd rect
			(at 0 0)
			(size 0.508 0.508)
			(layers "B.Cu" "B.Mask" "B.Paste")
			(net "GND")
		)
		(pad "2" smd rect
			(at 0 0.889)
			(size 0.508 0.508)
			(layers "B.Cu" "B.Mask" "B.Paste")
			(net "PD_PIROM_CPU0_ADDR0")
		)
		(zone
			(layer "B.Cu")
			(hatch none 0.5)
			(connect_pads
				(clearance 0)
			)
			(min_thickness 0.25)
			(keepout
				(tracks not_allowed)
				(vias allowed)
				(pads allowed)
				(copperpour not_allowed)
				(footprints allowed)
			)
			(placement
				(enabled no)
				(sheetname "")
			)
			(fill
				(thermal_gap 0.5)
				(thermal_bridge_width 0.5)
				(island_removal_mode 0)
			)
			(polygon
				(pts
					(xy 193.5988 -103.3018) (xy 194.1068 -103.3018) (xy 194.1068 -102.9208) (xy 193.5988 -102.9208)
				)
			)
		)
		(zone
			(layer "B.Cu")
			(hatch none 0.5)
			(connect_pads
				(clearance 0)
			)
			(min_thickness 0.25)
			(keepout
				(tracks allowed)
				(vias not_allowed)
				(pads allowed)
				(copperpour not_allowed)
				(footprints allowed)
			)
			(placement
				(enabled no)
				(sheetname "")
			)
			(fill
				(thermal_gap 0.5)
				(thermal_bridge_width 0.5)
				(island_removal_mode 0)
			)
			(polygon
				(pts
					(xy 193.5988 -102.9208) (xy 194.1068 -102.9208) (xy 194.1068 -103.3018) (xy 193.5988 -103.3018)
				)
			)
		)
	)
	(footprint ""
		(layer "B.Cu")
		(at 446.381632 -34.7345 90)
		(property "Reference" "R25W22"
			(at 0 0 90)
			(layer "B.SilkS")
			(hide yes)
			(effects
				(font
					(size 1.27 1.27)
				)
				(justify mirror)
			)
		)
		(property "Value" "*"
			(at -0.064008 -4.108196 90)
			(unlocked yes)
			(layer "B.Fab")
			(hide yes)
			(effects
				(font
					(size 1.27 1.016)
					(thickness 0.1524)
				)
				(justify mirror)
			)
		)
		(property "Device Type" "120R2F-GP_RCL_GP-120R2F-GP,64.A"
			(at -0.064008 -5.632196 90)
			(unlocked yes)
			(layer "B.Fab")
			(hide yes)
			(effects
				(font
					(size 1.27 1.016)
					(thickness 0.1524)
				)
				(justify mirror)
			)
		)
		(duplicate_pad_numbers_are_jumpers no)
		(fp_line
			(start 0.508 -0.9398)
			(end 0.508 0.9398)
			(stroke
				(width 0.1524)
				(type default)
			)
			(layer "B.SilkS")
		)
		(fp_line
			(start -0.508 -0.9398)
			(end 0.508 -0.9398)
			(stroke
				(width 0.1524)
				(type default)
			)
			(layer "B.SilkS")
		)
		(fp_rect
			(start 0.508 0.9398)
			(end -0.508 -0.9398)
			(stroke
				(width 0)
				(type default)
			)
			(fill no)
			(layer "B.CrtYd")
		)
		(fp_rect
			(start 0.508 0.9398)
			(end -0.508 -0.9398)
			(stroke
				(width 0)
				(type default)
			)
			(fill no)
			(layer "B.Fab")
		)
		(pad "1" smd custom
			(at 0 -0.4445 270)
			(size 0.1397 0.1397)
			(layers "B.Cu" "B.Mask" "B.Paste")
			(net "GND")
			(options
				(clearance outline)
				(anchor circle)
			)
			(primitives
				(gr_poly
					(pts
						(arc
							(start -0.1778 0.2794)
							(mid -0.249642 0.249642)
							(end -0.2794 0.1778)
						)
						(arc
							(start -0.2794 -0.1778)
							(mid -0.249642 -0.249642)
							(end -0.1778 -0.2794)
						)
						(arc
							(start 0.1778 -0.2794)
							(mid 0.249642 -0.249642)
							(end 0.2794 -0.1778)
						)
						(arc
							(start 0.2794 0.1778)
							(mid 0.249642 0.249642)
							(end 0.1778 0.2794)
						)
					)
					(width 0)
					(fill yes)
				)
			)
		)
		(pad "2" smd custom
			(at 0 0.4445 270)
			(size 0.1397 0.1397)
			(layers "B.Cu" "B.Mask" "B.Paste")
			(net "BMC_M_A10")
			(options
				(clearance outline)
				(anchor circle)
			)
			(primitives
				(gr_poly
					(pts
						(arc
							(start -0.1778 0.2794)
							(mid -0.249642 0.249642)
							(end -0.2794 0.1778)
						)
						(arc
							(start -0.2794 -0.1778)
							(mid -0.249642 -0.249642)
							(end -0.1778 -0.2794)
						)
						(arc
							(start 0.1778 -0.2794)
							(mid 0.249642 -0.249642)
							(end 0.2794 -0.1778)
						)
						(arc
							(start 0.2794 0.1778)
							(mid 0.249642 0.249642)
							(end 0.1778 0.2794)
						)
					)
					(width 0)
					(fill yes)
				)
			)
		)
	)
	(footprint ""
		(layer "B.Cu")
		(at 412.186882 -106.565192 90)
		(property "Reference" "R7W22"
			(at 0.8382 -0.67818 90)
			(unlocked yes)
			(layer "B.SilkS")
			(effects
				(font
					(size 0.4064 0.254)
					(thickness 0.1524)
				)
				(justify left mirror)
			)
		)
		(property "Value" ""
			(at 0 0 90)
			(layer "B.Fab")
			(effects
				(font
					(size 1.27 1.27)
				)
				(justify mirror)
			)
		)
		(duplicate_pad_numbers_are_jumpers no)
		(fp_poly
			(pts
				(xy 0.2794 -0.1016) (xy -0.2794 -0.1016) (xy -0.2794 0.9906) (xy 0.2794 0.9906)
			)
			(stroke
				(width 0)
				(type default)
			)
			(fill no)
			(layer "B.CrtYd")
		)
		(fp_line
			(start 0.2794 -0.1016)
			(end 0.2794 0.9906)
			(stroke
				(width 0.1)
				(type default)
			)
			(layer "B.Fab")
		)
		(fp_line
			(start -0.2794 -0.1016)
			(end 0.2794 -0.1016)
			(stroke
				(width 0.1)
				(type default)
			)
			(layer "B.Fab")
		)
		(fp_line
			(start 0.2794 0.9906)
			(end -0.2794 0.9906)
			(stroke
				(width 0.1)
				(type default)
			)
			(layer "B.Fab")
		)
		(fp_line
			(start -0.2794 0.9906)
			(end -0.2794 -0.1016)
			(stroke
				(width 0.1)
				(type default)
			)
			(layer "B.Fab")
		)
		(pad "1" smd rect
			(at 0 0 270)
			(size 0.508 0.508)
			(layers "B.Cu" "B.Mask" "B.Paste")
			(net "P3V3_STBY")
		)
		(pad "2" smd rect
			(at 0 0.889 270)
			(size 0.508 0.508)
			(layers "B.Cu" "B.Mask" "B.Paste")
			(net "FM_BMC_ENABLE_N")
		)
		(zone
			(layer "B.Cu")
			(hatch none 0.5)
			(connect_pads
				(clearance 0)
			)
			(min_thickness 0.25)
			(keepout
				(tracks allowed)
				(vias not_allowed)
				(pads allowed)
				(copperpour not_allowed)
				(footprints allowed)
			)
			(placement
				(enabled no)
				(sheetname "")
			)
			(fill
				(thermal_gap 0.5)
				(thermal_bridge_width 0.5)
				(island_removal_mode 0)
			)
			(polygon
				(pts
					(xy 412.440882 -106.819192) (xy 412.440882 -106.311192) (xy 412.821882 -106.311192) (xy 412.821882 -106.819192)
				)
			)
		)
		(zone
			(layer "B.Cu")
			(hatch none 0.5)
			(connect_pads
				(clearance 0)
			)
			(min_thickness 0.25)
			(keepout
				(tracks not_allowed)
				(vias allowed)
				(pads allowed)
				(copperpour not_allowed)
				(footprints allowed)
			)
			(placement
				(enabled no)
				(sheetname "")
			)
			(fill
				(thermal_gap 0.5)
				(thermal_bridge_width 0.5)
				(island_removal_mode 0)
			)
			(polygon
				(pts
					(xy 412.821882 -106.819192) (xy 412.821882 -106.311192) (xy 412.440882 -106.311192) (xy 412.440882 -106.819192)
				)
			)
		)
	)
	(footprint ""
		(layer "B.Cu")
		(at 407.5176 -29.4132 180)
		(property "Reference" "R25W149"
			(at 0.8382 -0.67818 180)
			(unlocked yes)
			(layer "B.SilkS")
			(effects
				(font
					(size 0.4064 0.254)
					(thickness 0.1524)
				)
				(justify left mirror)
			)
		)
		(property "Value" ""
			(at 0 0 0)
			(layer "B.Fab")
			(effects
				(font
					(size 1.27 1.27)
				)
				(justify mirror)
			)
		)
		(duplicate_pad_numbers_are_jumpers no)
		(fp_poly
			(pts
				(xy 0.2794 -0.1016) (xy -0.2794 -0.1016) (xy -0.2794 0.9906) (xy 0.2794 0.9906)
			)
			(stroke
				(width 0)
				(type default)
			)
			(fill no)
			(layer "B.CrtYd")
		)
		(fp_line
			(start 0.2794 0.9906)
			(end -0.2794 0.9906)
			(stroke
				(width 0.1)
				(type default)
			)
			(layer "B.Fab")
		)
		(fp_line
			(start 0.2794 -0.1016)
			(end 0.2794 0.9906)
			(stroke
				(width 0.1)
				(type default)
			)
			(layer "B.Fab")
		)
		(fp_line
			(start -0.2794 0.9906)
			(end -0.2794 -0.1016)
			(stroke
				(width 0.1)
				(type default)
			)
			(layer "B.Fab")
		)
		(fp_line
			(start -0.2794 -0.1016)
			(end 0.2794 -0.1016)
			(stroke
				(width 0.1)
				(type default)
			)
			(layer "B.Fab")
		)
		(pad "1" smd rect
			(at 0 0)
			(size 0.508 0.508)
			(layers "B.Cu" "B.Mask" "B.Paste")
			(net "GND")
		)
		(pad "2" smd rect
			(at 0 0.889)
			(size 0.508 0.508)
			(layers "B.Cu" "B.Mask" "B.Paste")
			(net "TP_RGMII1TXD2_GPIOT4")
		)
		(zone
			(layer "B.Cu")
			(hatch none 0.5)
			(connect_pads
				(clearance 0)
			)
			(min_thickness 0.25)
			(keepout
				(tracks not_allowed)
				(vias allowed)
				(pads allowed)
				(copperpour not_allowed)
				(footprints allowed)
			)
			(placement
				(enabled no)
				(sheetname "")
			)
			(fill
				(thermal_gap 0.5)
				(thermal_bridge_width 0.5)
				(island_removal_mode 0)
			)
			(polygon
				(pts
					(xy 407.2636 -30.0482) (xy 407.7716 -30.0482) (xy 407.7716 -29.6672) (xy 407.2636 -29.6672)
				)
			)
		)
		(zone
			(layer "B.Cu")
			(hatch none 0.5)
			(connect_pads
				(clearance 0)
			)
			(min_thickness 0.25)
			(keepout
				(tracks allowed)
				(vias not_allowed)
				(pads allowed)
				(copperpour not_allowed)
				(footprints allowed)
			)
			(placement
				(enabled no)
				(sheetname "")
			)
			(fill
				(thermal_gap 0.5)
				(thermal_bridge_width 0.5)
				(island_removal_mode 0)
			)
			(polygon
				(pts
					(xy 407.2636 -29.6672) (xy 407.7716 -29.6672) (xy 407.7716 -30.0482) (xy 407.2636 -30.0482)
				)
			)
		)
	)
	(footprint ""
		(layer "B.Cu")
		(at 88.392 -8.1534 90)
		(property "Reference" "C8U4"
			(at -1.848866 0.752348 90)
			(unlocked yes)
			(layer "B.SilkS")
			(effects
				(font
					(size 1.27 0.9652)
					(thickness 0.1524)
				)
				(justify mirror)
			)
		)
		(property "Value" ""
			(at 0 0 90)
			(layer "B.Fab")
			(effects
				(font
					(size 1.27 1.27)
				)
				(justify mirror)
			)
		)
		(duplicate_pad_numbers_are_jumpers no)
		(fp_rect
			(start 0.500126 1.598422)
			(end -0.500126 -0.201422)
			(stroke
				(width 0)
				(type default)
			)
			(fill no)
			(layer "B.CrtYd")
		)
		(fp_line
			(start 0.500126 -0.201422)
			(end -0.500126 -0.201422)
			(stroke
				(width 0.1)
				(type default)
			)
			(layer "B.Fab")
		)
		(fp_line
			(start -0.500126 -0.201422)
			(end -0.500126 1.598422)
			(stroke
				(width 0.1)
				(type default)
			)
			(layer "B.Fab")
		)
		(fp_line
			(start 0.500126 1.598422)
			(end 0.500126 -0.201422)
			(stroke
				(width 0.1)
				(type default)
			)
			(layer "B.Fab")
		)
		(fp_line
			(start -0.500126 1.598422)
			(end 0.500126 1.598422)
			(stroke
				(width 0.1)
				(type default)
			)
			(layer "B.Fab")
		)
		(pad "1" smd rect
			(at 0 0)
			(size 0.889 0.9906)
			(layers "B.Cu" "B.Mask" "B.Paste")
			(net "PVDDQ_GHJ")
		)
		(pad "2" smd rect
			(at 0 1.397)
			(size 0.889 0.9906)
			(layers "B.Cu" "B.Mask" "B.Paste")
			(net "GND")
		)
		(zone
			(layer "B.Cu")
			(hatch none 0.5)
			(connect_pads
				(clearance 0)
			)
			(min_thickness 0.25)
			(keepout
				(tracks allowed)
				(vias not_allowed)
				(pads allowed)
				(copperpour not_allowed)
				(footprints allowed)
			)
			(placement
				(enabled no)
				(sheetname "")
			)
			(fill
				(thermal_gap 0.5)
				(thermal_bridge_width 0.5)
				(island_removal_mode 0)
			)
			(polygon
				(pts
					(xy 89.3445 -8.6487) (xy 88.8365 -8.6487) (xy 88.8365 -7.6581) (xy 89.3445 -7.6581)
				)
			)
		)
		(zone
			(layer "B.Cu")
			(hatch none 0.5)
			(connect_pads
				(clearance 0)
			)
			(min_thickness 0.25)
			(keepout
				(tracks not_allowed)
				(vias allowed)
				(pads allowed)
				(copperpour not_allowed)
				(footprints allowed)
			)
			(placement
				(enabled no)
				(sheetname "")
			)
			(fill
				(thermal_gap 0.5)
				(thermal_bridge_width 0.5)
				(island_removal_mode 0)
			)
			(polygon
				(pts
					(xy 89.3445 -8.6487) (xy 88.8365 -8.6487) (xy 88.8365 -7.6581) (xy 89.3445 -7.6581)
				)
			)
		)
	)
	(footprint ""
		(layer "B.Cu")
		(at 330.091288 -63.38824 90)
		(property "Reference" "R3R14"
			(at 0 0 90)
			(layer "B.SilkS")
			(hide yes)
			(effects
				(font
					(size 1.27 1.27)
				)
				(justify mirror)
			)
		)
		(property "Value" ""
			(at 0 0 90)
			(layer "B.Fab")
			(effects
				(font
					(size 1.27 1.27)
				)
				(justify mirror)
			)
		)
		(duplicate_pad_numbers_are_jumpers no)
		(fp_poly
			(pts
				(xy 0.2794 -0.1016) (xy -0.2794 -0.1016) (xy -0.2794 0.9906) (xy 0.2794 0.9906)
			)
			(stroke
				(width 0)
				(type default)
			)
			(fill no)
			(layer "B.CrtYd")
		)
		(fp_line
			(start 0.2794 -0.1016)
			(end 0.2794 0.9906)
			(stroke
				(width 0.1)
				(type default)
			)
			(layer "B.Fab")
		)
		(fp_line
			(start -0.2794 -0.1016)
			(end 0.2794 -0.1016)
			(stroke
				(width 0.1)
				(type default)
			)
			(layer "B.Fab")
		)
		(fp_line
			(start 0.2794 0.9906)
			(end -0.2794 0.9906)
			(stroke
				(width 0.1)
				(type default)
			)
			(layer "B.Fab")
		)
		(fp_line
			(start -0.2794 0.9906)
			(end -0.2794 -0.1016)
			(stroke
				(width 0.1)
				(type default)
			)
			(layer "B.Fab")
		)
		(pad "1" smd rect
			(at 0 0 270)
			(size 0.508 0.508)
			(layers "B.Cu" "B.Mask" "B.Paste")
			(net "SMB_DDR_DEF_SDA_G_R")
		)
		(pad "2" smd rect
			(at 0 0.889 270)
			(size 0.508 0.508)
			(layers "B.Cu" "B.Mask" "B.Paste")
			(net "SMB_DDR_DEF_SDA_G")
		)
		(zone
			(layer "B.Cu")
			(hatch none 0.5)
			(connect_pads
				(clearance 0)
			)
			(min_thickness 0.25)
			(keepout
				(tracks allowed)
				(vias not_allowed)
				(pads allowed)
				(copperpour not_allowed)
				(footprints allowed)
			)
			(placement
				(enabled no)
				(sheetname "")
			)
			(fill
				(thermal_gap 0.5)
				(thermal_bridge_width 0.5)
				(island_removal_mode 0)
			)
			(polygon
				(pts
					(xy 330.345288 -63.64224) (xy 330.345288 -63.13424) (xy 330.726288 -63.13424) (xy 330.726288 -63.64224)
				)
			)
		)
		(zone
			(layer "B.Cu")
			(hatch none 0.5)
			(connect_pads
				(clearance 0)
			)
			(min_thickness 0.25)
			(keepout
				(tracks not_allowed)
				(vias allowed)
				(pads allowed)
				(copperpour not_allowed)
				(footprints allowed)
			)
			(placement
				(enabled no)
				(sheetname "")
			)
			(fill
				(thermal_gap 0.5)
				(thermal_bridge_width 0.5)
				(island_removal_mode 0)
			)
			(polygon
				(pts
					(xy 330.726288 -63.64224) (xy 330.726288 -63.13424) (xy 330.345288 -63.13424) (xy 330.345288 -63.64224)
				)
			)
		)
	)
)
